(kicad_pcb
	(version 20260206)
	(generator "pcbnew")
	(generator_version "10.0")
	(general
		(thickness 1.6)
		(legacy_teardrops no)
	)
	(paper "A4")
	(title_block
		(title "04192023_DAF0TMB3IC0_F0TG_MB_C_brd_V02_OCP.brd")
		(comment 1 "Grand Teton / footprint 2350 of 8354 (J19), pads 114-226 of 291")
	)
	(layers
		(0 "F.Cu" signal "TOP")
		(4 "In1.Cu" signal "GND")
		(6 "In2.Cu" signal "IN1")
		(8 "In3.Cu" signal "GND1")
		(10 "In4.Cu" signal "IN2")
		(12 "In5.Cu" signal "GND2")
		(14 "In6.Cu" signal "IN3")
		(16 "In7.Cu" signal "GND3")
		(18 "In8.Cu" signal "VCC")
		(20 "In9.Cu" signal "VCC1")
		(22 "In10.Cu" signal "GND4")
		(24 "In11.Cu" signal "IN4")
		(26 "In12.Cu" signal "GND5")
		(28 "In13.Cu" signal "IN5")
		(30 "In14.Cu" signal "GND6")
		(32 "In15.Cu" signal "IN6")
		(34 "In16.Cu" signal "GND7")
		(2 "B.Cu" signal "BOTTOM")
		(9 "F.Adhes" user "F.Adhesive")
		(11 "B.Adhes" user "B.Adhesive")
		(13 "F.Paste" user "Package Geometry/Pastemask Top")
		(15 "B.Paste" user "Package Geometry/Pastemask Bottom")
		(5 "F.SilkS" user "Ref Des/Silkscreen Top")
		(7 "B.SilkS" user "Ref Des/Silkscreen Bottom")
		(1 "F.Mask" user "Board Geometry/Soldermask Top")
		(3 "B.Mask" user "Board Geometry/Soldermask Bottom")
		(17 "Dwgs.User" user "User.Drawings")
		(19 "Cmts.User" user "User.Comments")
		(21 "Eco1.User" user "User.Eco1")
		(23 "Eco2.User" user "User.Eco2")
		(25 "Edge.Cuts" user "Board Geometry/Outline")
		(27 "Margin" user)
		(31 "F.CrtYd" user "Package Geometry/Place Bound Top")
		(29 "B.CrtYd" user "Package Geometry/Place Bound Bottom")
		(35 "F.Fab" user "Ref Des/Assembly Top")
		(33 "B.Fab" user "Ref Des/Assembly Bottom")
	)
	(footprint ""
		(layer "F.Cu")
		(at 282.685998 -255.560068 180)
		(property "Reference" "J19"
			(at -2.2098 -81.984088 0)
			(unlocked yes)
			(layer "F.SilkS")
			(effects
				(font
					(size 0.7874 0.5842)
					(thickness 0.1524)
				)
			)
		)
		(property "Value" ""
			(at 0 0 180)
			(layer "F.Fab")
			(effects
				(font
					(size 1.27 1.27)
				)
			)
		)
		(duplicate_pad_numbers_are_jumpers no)
		(pad "114" smd rect
			(at -2.050034 37.824918 90)
			(size 0.519938 1.4986)
			(layers "F.Cu" "F.Mask" "F.Paste")
			(net "GND")
		)
		(pad "115" smd rect
			(at -2.050034 38.675056 90)
			(size 0.519938 1.4986)
			(layers "F.Cu" "F.Mask" "F.Paste")
			(net "M_D_CPU0_SB_DQS_DP<1>")
		)
		(pad "116" smd rect
			(at -2.050034 39.52494 90)
			(size 0.519938 1.4986)
			(layers "F.Cu" "F.Mask" "F.Paste")
			(net "M_D_CPU0_SB_DQS_DN<1>")
		)
		(pad "117" smd rect
			(at -2.050034 40.375078 90)
			(size 0.519938 1.4986)
			(layers "F.Cu" "F.Mask" "F.Paste")
			(net "GND")
		)
		(pad "118" smd rect
			(at -2.050034 41.224962 90)
			(size 0.519938 1.4986)
			(layers "F.Cu" "F.Mask" "F.Paste")
			(net "M_D_CPU0_SB_DQ<12>")
		)
		(pad "119" smd rect
			(at -2.050034 42.0751 90)
			(size 0.519938 1.4986)
			(layers "F.Cu" "F.Mask" "F.Paste")
			(net "GND")
		)
		(pad "120" smd rect
			(at -2.050034 42.924984 90)
			(size 0.519938 1.4986)
			(layers "F.Cu" "F.Mask" "F.Paste")
			(net "M_D_CPU0_SB_DQ<13>")
		)
		(pad "121" smd rect
			(at -2.050034 43.775122 90)
			(size 0.519938 1.4986)
			(layers "F.Cu" "F.Mask" "F.Paste")
			(net "GND")
		)
		(pad "122" smd rect
			(at -2.050034 44.625006 90)
			(size 0.519938 1.4986)
			(layers "F.Cu" "F.Mask" "F.Paste")
			(net "M_D_CPU0_SB_DQ<16>")
		)
		(pad "123" smd rect
			(at -2.050034 45.47489 90)
			(size 0.519938 1.4986)
			(layers "F.Cu" "F.Mask" "F.Paste")
			(net "GND")
		)
		(pad "124" smd rect
			(at -2.050034 46.325028 90)
			(size 0.519938 1.4986)
			(layers "F.Cu" "F.Mask" "F.Paste")
			(net "M_D_CPU0_SB_DQ<17>")
		)
		(pad "125" smd rect
			(at -2.050034 47.174912 90)
			(size 0.519938 1.4986)
			(layers "F.Cu" "F.Mask" "F.Paste")
			(net "GND")
		)
		(pad "126" smd rect
			(at -2.050034 48.02505 90)
			(size 0.519938 1.4986)
			(layers "F.Cu" "F.Mask" "F.Paste")
			(net "M_D_CPU0_SB_DQS_DP<2>")
		)
		(pad "127" smd rect
			(at -2.050034 48.874934 90)
			(size 0.519938 1.4986)
			(layers "F.Cu" "F.Mask" "F.Paste")
			(net "M_D_CPU0_SB_DQS_DN<2>")
		)
		(pad "128" smd rect
			(at -2.050034 49.725072 90)
			(size 0.519938 1.4986)
			(layers "F.Cu" "F.Mask" "F.Paste")
			(net "GND")
		)
		(pad "129" smd rect
			(at -2.050034 50.574956 90)
			(size 0.519938 1.4986)
			(layers "F.Cu" "F.Mask" "F.Paste")
			(net "M_D_CPU0_SB_DQ<20>")
		)
		(pad "130" smd rect
			(at -2.050034 51.425094 90)
			(size 0.519938 1.4986)
			(layers "F.Cu" "F.Mask" "F.Paste")
			(net "GND")
		)
		(pad "131" smd rect
			(at -2.050034 52.274978 90)
			(size 0.519938 1.4986)
			(layers "F.Cu" "F.Mask" "F.Paste")
			(net "M_D_CPU0_SB_DQ<21>")
		)
		(pad "132" smd rect
			(at -2.050034 53.125116 90)
			(size 0.519938 1.4986)
			(layers "F.Cu" "F.Mask" "F.Paste")
			(net "GND")
		)
		(pad "133" smd rect
			(at -2.050034 53.975 90)
			(size 0.519938 1.4986)
			(layers "F.Cu" "F.Mask" "F.Paste")
			(net "M_D_CPU0_SB_DQ<24>")
		)
		(pad "134" smd rect
			(at -2.050034 54.824884 90)
			(size 0.519938 1.4986)
			(layers "F.Cu" "F.Mask" "F.Paste")
			(net "GND")
		)
		(pad "135" smd rect
			(at -2.050034 55.675022 90)
			(size 0.519938 1.4986)
			(layers "F.Cu" "F.Mask" "F.Paste")
			(net "M_D_CPU0_SB_DQ<25>")
		)
		(pad "136" smd rect
			(at -2.050034 56.524906 90)
			(size 0.519938 1.4986)
			(layers "F.Cu" "F.Mask" "F.Paste")
			(net "GND")
		)
		(pad "137" smd rect
			(at -2.050034 57.375044 90)
			(size 0.519938 1.4986)
			(layers "F.Cu" "F.Mask" "F.Paste")
			(net "M_D_CPU0_SB_DQS_DP<3>")
		)
		(pad "138" smd rect
			(at -2.050034 58.224928 90)
			(size 0.519938 1.4986)
			(layers "F.Cu" "F.Mask" "F.Paste")
			(net "M_D_CPU0_SB_DQS_DN<3>")
		)
		(pad "139" smd rect
			(at -2.050034 59.075066 90)
			(size 0.519938 1.4986)
			(layers "F.Cu" "F.Mask" "F.Paste")
			(net "GND")
		)
		(pad "140" smd rect
			(at -2.050034 59.92495 90)
			(size 0.519938 1.4986)
			(layers "F.Cu" "F.Mask" "F.Paste")
			(net "M_D_CPU0_SB_DQ<28>")
		)
		(pad "141" smd rect
			(at -2.050034 60.775088 90)
			(size 0.519938 1.4986)
			(layers "F.Cu" "F.Mask" "F.Paste")
			(net "GND")
		)
		(pad "142" smd rect
			(at -2.050034 61.624972 90)
			(size 0.519938 1.4986)
			(layers "F.Cu" "F.Mask" "F.Paste")
			(net "M_D_CPU0_SB_DQ<29>")
		)
		(pad "143" smd rect
			(at -2.050034 62.47511 90)
			(size 0.519938 1.4986)
			(layers "F.Cu" "F.Mask" "F.Paste")
			(net "GND")
		)
		(pad "144" smd rect
			(at -2.050034 63.324994 90)
			(size 0.519938 1.4986)
			(layers "F.Cu" "F.Mask" "F.Paste")
			(net "Net_2292")
		)
		(pad "145" smd rect
			(at 2.050034 -63.324994 90)
			(size 0.519938 1.4986)
			(layers "F.Cu" "F.Mask" "F.Paste")
			(net "P12V_MEM_CPU0")
		)
		(pad "146" smd rect
			(at 2.050034 -62.47511 90)
			(size 0.519938 1.4986)
			(layers "F.Cu" "F.Mask" "F.Paste")
			(net "P12V_MEM_CPU0")
		)
		(pad "147" smd rect
			(at 2.050034 -61.624972 90)
			(size 0.519938 1.4986)
			(layers "F.Cu" "F.Mask" "F.Paste")
			(net "PWRGD_CHD_CPU0_DIMM")
		)
		(pad "148" smd rect
			(at 2.050034 -60.775088 90)
			(size 0.519938 1.4986)
			(layers "F.Cu" "F.Mask" "F.Paste")
			(net "PD_CHD_CPU0_DIMM_SAA")
		)
		(pad "149" smd rect
			(at 2.050034 -59.92495 90)
			(size 0.519938 1.4986)
			(layers "F.Cu" "F.Mask" "F.Paste")
			(net "Net_2293")
		)
		(pad "150" smd rect
			(at 2.050034 -59.075066 90)
			(size 0.519938 1.4986)
			(layers "F.Cu" "F.Mask" "F.Paste")
			(net "Net_2294")
		)
		(pad "151" smd rect
			(at 2.050034 -58.224928 90)
			(size 0.519938 1.4986)
			(layers "F.Cu" "F.Mask" "F.Paste")
			(net "GND")
		)
		(pad "152" smd rect
			(at 2.050034 -57.375044 90)
			(size 0.519938 1.4986)
			(layers "F.Cu" "F.Mask" "F.Paste")
			(net "M_D_CPU0_SA_DQ<2>")
		)
		(pad "153" smd rect
			(at 2.050034 -56.524906 90)
			(size 0.519938 1.4986)
			(layers "F.Cu" "F.Mask" "F.Paste")
			(net "GND")
		)
		(pad "154" smd rect
			(at 2.050034 -55.675022 90)
			(size 0.519938 1.4986)
			(layers "F.Cu" "F.Mask" "F.Paste")
			(net "M_D_CPU0_SA_DQ<3>")
		)
		(pad "155" smd rect
			(at 2.050034 -54.824884 90)
			(size 0.519938 1.4986)
			(layers "F.Cu" "F.Mask" "F.Paste")
			(net "GND")
		)
		(pad "156" smd rect
			(at 2.050034 -53.975 90)
			(size 0.519938 1.4986)
			(layers "F.Cu" "F.Mask" "F.Paste")
			(net "M_D_CPU0_SA_DQS_DN<5>")
		)
		(pad "157" smd rect
			(at 2.050034 -53.125116 90)
			(size 0.519938 1.4986)
			(layers "F.Cu" "F.Mask" "F.Paste")
			(net "M_D_CPU0_SA_DQS_DP<5>")
		)
		(pad "158" smd rect
			(at 2.050034 -52.274978 90)
			(size 0.519938 1.4986)
			(layers "F.Cu" "F.Mask" "F.Paste")
			(net "GND")
		)
		(pad "159" smd rect
			(at 2.050034 -51.425094 90)
			(size 0.519938 1.4986)
			(layers "F.Cu" "F.Mask" "F.Paste")
			(net "M_D_CPU0_SA_DQ<6>")
		)
		(pad "160" smd rect
			(at 2.050034 -50.574956 90)
			(size 0.519938 1.4986)
			(layers "F.Cu" "F.Mask" "F.Paste")
			(net "GND")
		)
		(pad "161" smd rect
			(at 2.050034 -49.725072 90)
			(size 0.519938 1.4986)
			(layers "F.Cu" "F.Mask" "F.Paste")
			(net "M_D_CPU0_SA_DQ<7>")
		)
		(pad "162" smd rect
			(at 2.050034 -48.874934 90)
			(size 0.519938 1.4986)
			(layers "F.Cu" "F.Mask" "F.Paste")
			(net "GND")
		)
		(pad "163" smd rect
			(at 2.050034 -48.02505 90)
			(size 0.519938 1.4986)
			(layers "F.Cu" "F.Mask" "F.Paste")
			(net "M_D_CPU0_SA_DQ<10>")
		)
		(pad "164" smd rect
			(at 2.050034 -47.174912 90)
			(size 0.519938 1.4986)
			(layers "F.Cu" "F.Mask" "F.Paste")
			(net "GND")
		)
		(pad "165" smd rect
			(at 2.050034 -46.325028 90)
			(size 0.519938 1.4986)
			(layers "F.Cu" "F.Mask" "F.Paste")
			(net "M_D_CPU0_SA_DQ<11>")
		)
		(pad "166" smd rect
			(at 2.050034 -45.47489 90)
			(size 0.519938 1.4986)
			(layers "F.Cu" "F.Mask" "F.Paste")
			(net "GND")
		)
		(pad "167" smd rect
			(at 2.050034 -44.625006 90)
			(size 0.519938 1.4986)
			(layers "F.Cu" "F.Mask" "F.Paste")
			(net "M_D_CPU0_SA_DQS_DN<6>")
		)
		(pad "168" smd rect
			(at 2.050034 -43.775122 90)
			(size 0.519938 1.4986)
			(layers "F.Cu" "F.Mask" "F.Paste")
			(net "M_D_CPU0_SA_DQS_DP<6>")
		)
		(pad "169" smd rect
			(at 2.050034 -42.924984 90)
			(size 0.519938 1.4986)
			(layers "F.Cu" "F.Mask" "F.Paste")
			(net "GND")
		)
		(pad "170" smd rect
			(at 2.050034 -42.0751 90)
			(size 0.519938 1.4986)
			(layers "F.Cu" "F.Mask" "F.Paste")
			(net "M_D_CPU0_SA_DQ<14>")
		)
		(pad "171" smd rect
			(at 2.050034 -41.224962 90)
			(size 0.519938 1.4986)
			(layers "F.Cu" "F.Mask" "F.Paste")
			(net "GND")
		)
		(pad "172" smd rect
			(at 2.050034 -40.375078 90)
			(size 0.519938 1.4986)
			(layers "F.Cu" "F.Mask" "F.Paste")
			(net "M_D_CPU0_SA_DQ<15>")
		)
		(pad "173" smd rect
			(at 2.050034 -39.52494 90)
			(size 0.519938 1.4986)
			(layers "F.Cu" "F.Mask" "F.Paste")
			(net "GND")
		)
		(pad "174" smd rect
			(at 2.050034 -38.675056 90)
			(size 0.519938 1.4986)
			(layers "F.Cu" "F.Mask" "F.Paste")
			(net "M_D_CPU0_SA_DQ<18>")
		)
		(pad "175" smd rect
			(at 2.050034 -37.824918 90)
			(size 0.519938 1.4986)
			(layers "F.Cu" "F.Mask" "F.Paste")
			(net "GND")
		)
		(pad "176" smd rect
			(at 2.050034 -36.975034 90)
			(size 0.519938 1.4986)
			(layers "F.Cu" "F.Mask" "F.Paste")
			(net "M_D_CPU0_SA_DQ<19>")
		)
		(pad "177" smd rect
			(at 2.050034 -36.124896 90)
			(size 0.519938 1.4986)
			(layers "F.Cu" "F.Mask" "F.Paste")
			(net "GND")
		)
		(pad "178" smd rect
			(at 2.050034 -35.275012 90)
			(size 0.519938 1.4986)
			(layers "F.Cu" "F.Mask" "F.Paste")
			(net "M_D_CPU0_SA_DQS_DN<7>")
		)
		(pad "179" smd rect
			(at 2.050034 -34.425128 90)
			(size 0.519938 1.4986)
			(layers "F.Cu" "F.Mask" "F.Paste")
			(net "M_D_CPU0_SA_DQS_DP<7>")
		)
		(pad "180" smd rect
			(at 2.050034 -33.57499 90)
			(size 0.519938 1.4986)
			(layers "F.Cu" "F.Mask" "F.Paste")
			(net "GND")
		)
		(pad "181" smd rect
			(at 2.050034 -32.725106 90)
			(size 0.519938 1.4986)
			(layers "F.Cu" "F.Mask" "F.Paste")
			(net "M_D_CPU0_SA_DQ<22>")
		)
		(pad "182" smd rect
			(at 2.050034 -31.874968 90)
			(size 0.519938 1.4986)
			(layers "F.Cu" "F.Mask" "F.Paste")
			(net "GND")
		)
		(pad "183" smd rect
			(at 2.050034 -31.025084 90)
			(size 0.519938 1.4986)
			(layers "F.Cu" "F.Mask" "F.Paste")
			(net "M_D_CPU0_SA_DQ<23>")
		)
		(pad "184" smd rect
			(at 2.050034 -30.174946 90)
			(size 0.519938 1.4986)
			(layers "F.Cu" "F.Mask" "F.Paste")
			(net "GND")
		)
		(pad "185" smd rect
			(at 2.050034 -29.325062 90)
			(size 0.519938 1.4986)
			(layers "F.Cu" "F.Mask" "F.Paste")
			(net "M_D_CPU0_SA_DQ<26>")
		)
		(pad "186" smd rect
			(at 2.050034 -28.474924 90)
			(size 0.519938 1.4986)
			(layers "F.Cu" "F.Mask" "F.Paste")
			(net "GND")
		)
		(pad "187" smd rect
			(at 2.050034 -27.62504 90)
			(size 0.519938 1.4986)
			(layers "F.Cu" "F.Mask" "F.Paste")
			(net "M_D_CPU0_SA_DQ<27>")
		)
		(pad "188" smd rect
			(at 2.050034 -26.774902 90)
			(size 0.519938 1.4986)
			(layers "F.Cu" "F.Mask" "F.Paste")
			(net "GND")
		)
		(pad "189" smd rect
			(at 2.050034 -25.925018 90)
			(size 0.519938 1.4986)
			(layers "F.Cu" "F.Mask" "F.Paste")
			(net "M_D_CPU0_SA_DQS_DN<8>")
		)
		(pad "190" smd rect
			(at 2.050034 -25.07488 90)
			(size 0.519938 1.4986)
			(layers "F.Cu" "F.Mask" "F.Paste")
			(net "M_D_CPU0_SA_DQS_DP<8>")
		)
		(pad "191" smd rect
			(at 2.050034 -24.224996 90)
			(size 0.519938 1.4986)
			(layers "F.Cu" "F.Mask" "F.Paste")
			(net "GND")
		)
		(pad "192" smd rect
			(at 2.050034 -23.375112 90)
			(size 0.519938 1.4986)
			(layers "F.Cu" "F.Mask" "F.Paste")
			(net "M_D_CPU0_SA_DQ<30>")
		)
		(pad "193" smd rect
			(at 2.050034 -22.524974 90)
			(size 0.519938 1.4986)
			(layers "F.Cu" "F.Mask" "F.Paste")
			(net "GND")
		)
		(pad "194" smd rect
			(at 2.050034 -21.67509 90)
			(size 0.519938 1.4986)
			(layers "F.Cu" "F.Mask" "F.Paste")
			(net "M_D_CPU0_SA_DQ<31>")
		)
		(pad "195" smd rect
			(at 2.050034 -20.824952 90)
			(size 0.519938 1.4986)
			(layers "F.Cu" "F.Mask" "F.Paste")
			(net "GND")
		)
		(pad "196" smd rect
			(at 2.050034 -19.975068 90)
			(size 0.519938 1.4986)
			(layers "F.Cu" "F.Mask" "F.Paste")
			(net "M_D_CPU0_SA_CB<2>")
		)
		(pad "197" smd rect
			(at 2.050034 -19.12493 90)
			(size 0.519938 1.4986)
			(layers "F.Cu" "F.Mask" "F.Paste")
			(net "GND")
		)
		(pad "198" smd rect
			(at 2.050034 -18.275046 90)
			(size 0.519938 1.4986)
			(layers "F.Cu" "F.Mask" "F.Paste")
			(net "M_D_CPU0_SA_CB<3>")
		)
		(pad "199" smd rect
			(at 2.050034 -17.424908 90)
			(size 0.519938 1.4986)
			(layers "F.Cu" "F.Mask" "F.Paste")
			(net "GND")
		)
		(pad "200" smd rect
			(at 2.050034 -16.575024 90)
			(size 0.519938 1.4986)
			(layers "F.Cu" "F.Mask" "F.Paste")
			(net "M_D_CPU0_SA_DQS_DN<9>")
		)
		(pad "201" smd rect
			(at 2.050034 -15.724886 90)
			(size 0.519938 1.4986)
			(layers "F.Cu" "F.Mask" "F.Paste")
			(net "M_D_CPU0_SA_DQS_DP<9>")
		)
		(pad "202" smd rect
			(at 2.050034 -14.875002 90)
			(size 0.519938 1.4986)
			(layers "F.Cu" "F.Mask" "F.Paste")
			(net "GND")
		)
		(pad "203" smd rect
			(at 2.050034 -14.025118 90)
			(size 0.519938 1.4986)
			(layers "F.Cu" "F.Mask" "F.Paste")
			(net "M_D_CPU0_SA_CB<6>")
		)
		(pad "204" smd rect
			(at 2.050034 -13.17498 90)
			(size 0.519938 1.4986)
			(layers "F.Cu" "F.Mask" "F.Paste")
			(net "GND")
		)
		(pad "205" smd rect
			(at 2.050034 -12.325096 90)
			(size 0.519938 1.4986)
			(layers "F.Cu" "F.Mask" "F.Paste")
			(net "M_D_CPU0_SA_CB<7>")
		)
		(pad "206" smd rect
			(at 2.050034 -11.474958 90)
			(size 0.519938 1.4986)
			(layers "F.Cu" "F.Mask" "F.Paste")
			(net "GND")
		)
		(pad "207" smd rect
			(at 2.050034 -10.625074 90)
			(size 0.519938 1.4986)
			(layers "F.Cu" "F.Mask" "F.Paste")
			(net "M_D_CPU0_RESET_N")
		)
		(pad "208" smd rect
			(at 2.050034 -9.774936 90)
			(size 0.519938 1.4986)
			(layers "F.Cu" "F.Mask" "F.Paste")
			(net "GND")
		)
		(pad "209" smd rect
			(at 2.050034 -8.925052 90)
			(size 0.519938 1.4986)
			(layers "F.Cu" "F.Mask" "F.Paste")
			(net "M_D_CPU0_SA_CS_N<1>")
		)
		(pad "210" smd rect
			(at 2.050034 -8.074914 90)
			(size 0.519938 1.4986)
			(layers "F.Cu" "F.Mask" "F.Paste")
			(net "GND")
		)
		(pad "211" smd rect
			(at 2.050034 -7.22503 90)
			(size 0.519938 1.4986)
			(layers "F.Cu" "F.Mask" "F.Paste")
			(net "M_D_CPU0_SA_CA<1>")
		)
		(pad "212" smd rect
			(at 2.050034 -6.374892 90)
			(size 0.519938 1.4986)
			(layers "F.Cu" "F.Mask" "F.Paste")
			(net "GND")
		)
		(pad "213" smd rect
			(at 2.050034 -5.525008 90)
			(size 0.519938 1.4986)
			(layers "F.Cu" "F.Mask" "F.Paste")
			(net "M_D_CPU0_SA_CA<3>")
		)
		(pad "214" smd rect
			(at 2.050034 -4.675124 90)
			(size 0.519938 1.4986)
			(layers "F.Cu" "F.Mask" "F.Paste")
			(net "GND")
		)
		(pad "215" smd rect
			(at 2.050034 -3.824986 90)
			(size 0.519938 1.4986)
			(layers "F.Cu" "F.Mask" "F.Paste")
			(net "M_D_CPU0_SA_CA<5>")
		)
		(pad "216" smd rect
			(at 2.050034 -2.975102 90)
			(size 0.519938 1.4986)
			(layers "F.Cu" "F.Mask" "F.Paste")
			(net "GND")
		)
		(pad "217" smd rect
			(at 2.050034 -2.124964 90)
			(size 0.519938 1.4986)
			(layers "F.Cu" "F.Mask" "F.Paste")
			(net "M_D_CPU0_CLK_DP<0>")
		)
		(pad "218" smd rect
			(at 2.050034 -1.27508 90)
			(size 0.519938 1.4986)
			(layers "F.Cu" "F.Mask" "F.Paste")
			(net "M_D_CPU0_CLK_DN<0>")
		)
		(pad "219" smd rect
			(at 2.050034 -0.424942 90)
			(size 0.519938 1.4986)
			(layers "F.Cu" "F.Mask" "F.Paste")
			(net "GND")
		)
		(pad "220" smd rect
			(at 2.050034 5.525008 90)
			(size 0.519938 1.4986)
			(layers "F.Cu" "F.Mask" "F.Paste")
			(net "Net_2295")
		)
		(pad "221" smd rect
			(at 2.050034 6.374892 90)
			(size 0.519938 1.4986)
			(layers "F.Cu" "F.Mask" "F.Paste")
			(net "M_D_CPU0_SB_CA<1>")
		)
		(pad "222" smd rect
			(at 2.050034 7.22503 90)
			(size 0.519938 1.4986)
			(layers "F.Cu" "F.Mask" "F.Paste")
			(net "GND")
		)
		(pad "223" smd rect
			(at 2.050034 8.074914 90)
			(size 0.519938 1.4986)
			(layers "F.Cu" "F.Mask" "F.Paste")
			(net "M_D_CPU0_SB_CA<3>")
		)
		(pad "224" smd rect
			(at 2.050034 8.925052 90)
			(size 0.519938 1.4986)
			(layers "F.Cu" "F.Mask" "F.Paste")
			(net "GND")
		)
		(pad "225" smd rect
			(at 2.050034 9.774936 90)
			(size 0.519938 1.4986)
			(layers "F.Cu" "F.Mask" "F.Paste")
			(net "M_D_CPU0_SB_CA<5>")
		)
		(pad "226" smd rect
			(at 2.050034 10.625074 90)
			(size 0.519938 1.4986)
			(layers "F.Cu" "F.Mask" "F.Paste")
			(net "GND")
		)
	)
)
